# BASEBOARD_FAB2 (Tioga Pass) — schematic netlist excerpt (pin names and nets, part order shuffled) for the footprints in the layout excerpt that follows; sources: Cadence DE-HDL packaged netlist, KiCad conversion of Wiwynn_Tioga_Pass_MB.brd

C12W4  CAP  47.0PF 50V 5% COG  pkg 0402LF  page 197 : A = VR_PVDDQ_KLM_AIINSEN ; B = VR_PVDDQ_KLM_VINSEN
R4B6  RES  7.87K 1.0% CHIP  pkg 0402  page 234 : A = VR_PVPP_KLM_ISET ; B = AGND_PVPP_KLM
TH9A1  MTG_KEYHOLE  EMPTY  pkg TH  page 195 : \1\ = GND

(kicad_pcb
	(version 20260206)
	(generator "pcbnew")
	(generator_version "10.0")
	(general
		(thickness 1.6)
		(legacy_teardrops no)
	)
	(paper "A4")
	(title_block
		(title "Wiwynn_Tioga_Pass_MB.brd")
		(comment 1 "Tioga Pass / footprints 1205-1207 of 4770")
	)
	(layers
		(0 "F.Cu" signal "TOP")
		(4 "In1.Cu" signal "L2GND")
		(6 "In2.Cu" signal "L3")
		(8 "In3.Cu" signal "L4GND")
		(10 "In4.Cu" signal "L5")
		(12 "In5.Cu" signal "L6GND")
		(14 "In6.Cu" signal "L7VCC")
		(16 "In7.Cu" signal "L8VCC")
		(18 "In8.Cu" signal "L9GND")
		(20 "In9.Cu" signal "L10")
		(22 "In10.Cu" signal "L11GND")
		(24 "In11.Cu" signal "L12")
		(26 "In12.Cu" signal "L13GND")
		(2 "B.Cu" signal "BOTTOM")
		(9 "F.Adhes" user "F.Adhesive")
		(11 "B.Adhes" user "B.Adhesive")
		(13 "F.Paste" user "Package Geometry/Pastemask Top")
		(15 "B.Paste" user "Package Geometry/Pastemask Bottom")
		(5 "F.SilkS" user "Ref Des/Silkscreen Top")
		(7 "B.SilkS" user "Ref Des/Silkscreen Bottom")
		(1 "F.Mask" user "Board Geometry/Soldermask Top")
		(3 "B.Mask" user "Board Geometry/Soldermask Bottom")
		(17 "Dwgs.User" user "User.Drawings")
		(19 "Cmts.User" user "User.Comments")
		(21 "Eco1.User" user "User.Eco1")
		(23 "Eco2.User" user "User.Eco2")
		(25 "Edge.Cuts" user "Board Geometry/Outline")
		(27 "Margin" user)
		(31 "F.CrtYd" user "Package Geometry/Place Bound Top")
		(29 "B.CrtYd" user "Package Geometry/Place Bound Bottom")
		(35 "F.Fab" user "Ref Des/Assembly Top")
		(33 "B.Fab" user "Ref Des/Assembly Bottom")
	)
	(footprint ""
		(layer "F.Cu")
		(at 177.927 -131.7625)
		(property "Reference" "R4B6"
			(at 0 0 0)
			(layer "F.SilkS")
			(hide yes)
			(effects
				(font
					(size 1.27 1.27)
				)
			)
		)
		(property "Value" ""
			(at 0 0 0)
			(layer "F.Fab")
			(effects
				(font
					(size 1.27 1.27)
				)
			)
		)
		(duplicate_pad_numbers_are_jumpers no)
		(fp_poly
			(pts
				(xy -0.2794 -0.1016) (xy 0.2794 -0.1016) (xy 0.2794 0.9906) (xy -0.2794 0.9906)
			)
			(stroke
				(width 0)
				(type default)
			)
			(fill no)
			(layer "F.CrtYd")
		)
		(fp_line
			(start -0.2794 -0.1016)
			(end -0.2794 0.9906)
			(stroke
				(width 0.1)
				(type default)
			)
			(layer "F.Fab")
		)
		(fp_line
			(start -0.2794 0.9906)
			(end 0.2794 0.9906)
			(stroke
				(width 0.1)
				(type default)
			)
			(layer "F.Fab")
		)
		(fp_line
			(start 0.2794 -0.1016)
			(end -0.2794 -0.1016)
			(stroke
				(width 0.1)
				(type default)
			)
			(layer "F.Fab")
		)
		(fp_line
			(start 0.2794 0.9906)
			(end 0.2794 -0.1016)
			(stroke
				(width 0.1)
				(type default)
			)
			(layer "F.Fab")
		)
		(pad "1" smd rect
			(at 0 0)
			(size 0.508 0.508)
			(layers "F.Cu" "F.Mask" "F.Paste")
			(net "VR_PVPP_KLM_ISET")
		)
		(pad "2" smd rect
			(at 0 0.889)
			(size 0.508 0.508)
			(layers "F.Cu" "F.Mask" "F.Paste")
			(net "AGND_PVPP_KLM")
		)
		(zone
			(layer "F.Cu")
			(hatch none 0.5)
			(connect_pads
				(clearance 0)
			)
			(min_thickness 0.25)
			(keepout
				(tracks allowed)
				(vias not_allowed)
				(pads allowed)
				(copperpour not_allowed)
				(footprints allowed)
			)
			(placement
				(enabled no)
				(sheetname "")
			)
			(fill
				(thermal_gap 0.5)
				(thermal_bridge_width 0.5)
				(island_removal_mode 0)
			)
			(polygon
				(pts
					(xy 177.673 -131.5085) (xy 178.181 -131.5085) (xy 178.181 -131.1275) (xy 177.673 -131.1275)
				)
			)
		)
		(zone
			(layer "F.Cu")
			(hatch none 0.5)
			(connect_pads
				(clearance 0)
			)
			(min_thickness 0.25)
			(keepout
				(tracks not_allowed)
				(vias allowed)
				(pads allowed)
				(copperpour not_allowed)
				(footprints allowed)
			)
			(placement
				(enabled no)
				(sheetname "")
			)
			(fill
				(thermal_gap 0.5)
				(thermal_bridge_width 0.5)
				(island_removal_mode 0)
			)
			(polygon
				(pts
					(xy 177.673 -131.1275) (xy 178.181 -131.1275) (xy 178.181 -131.5085) (xy 177.673 -131.5085)
				)
			)
		)
	)
	(footprint ""
		(layer "F.Cu")
		(at 471.000074 -155.10002 90)
		(property "Reference" "TH9A1"
			(at 3.36931 -4.656074 0)
			(unlocked yes)
			(layer "F.SilkS")
			(effects
				(font
					(size 0.7874 0.5842)
					(thickness 0.1524)
				)
				(justify left)
			)
		)
		(property "Value" ""
			(at 0 0 90)
			(layer "F.Fab")
			(effects
				(font
					(size 1.27 1.27)
				)
			)
		)
		(duplicate_pad_numbers_are_jumpers no)
		(fp_poly
			(pts
				(arc
					(start 3.0226 0.68834)
					(mid 3.042235 0.827855)
					(end 3.099562 0.956564)
				)
				(arc
					(start 3.099562 0.956564)
					(mid 4.012804 3.550073)
					(end 3.042158 6.12267)
				)
				(arc
					(start 3.042158 6.12267)
					(mid 0 7.518589)
					(end -3.042158 6.12267)
				)
				(arc
					(start -3.042158 6.12267)
					(mid -4.012854 3.55061)
					(end -3.100324 0.957326)
				)
				(arc
					(start -3.100324 0.957326)
					(mid -3.042498 0.827518)
					(end -3.0226 0.686816)
				)
				(arc
					(start -3.0226 -0.000254)
					(mid -2.137121 -2.137227)
					(end 0 -3.022346)
				)
				(arc
					(start 0 -3.022346)
					(mid 2.137227 -2.136973)
					(end 3.0226 0.000254)
				)
			)
			(stroke
				(width 0)
				(type default)
			)
			(fill no)
			(layer "F.CrtYd")
		)
		(pad "1" thru_hole custom
			(at 0 0 90)
			(size 2.00667 2.00667)
			(drill 0.3048)
			(layers "*.Cu" "*.Mask")
			(remove_unused_layers no)
			(net "GND")
			(clearance -0.889)
			(options
				(clearance outline)
				(anchor circle)
			)
			(primitives
				(gr_poly
					(pts
						(arc
							(start 3.042158 3.874516)
							(mid 0 5.270435)
							(end -3.042158 3.874516)
						)
						(arc
							(start -3.042158 3.874516)
							(mid -4.012854 1.302456)
							(end -3.100324 -1.290828)
						)
						(arc
							(start -3.100324 -1.290828)
							(mid -3.042498 -1.420636)
							(end -3.0226 -1.561338)
						)
						(arc
							(start -3.0226 -2.248408)
							(mid -2.137121 -4.385381)
							(end 0 -5.2705)
						)
						(arc
							(start 0 -5.2705)
							(mid 2.137227 -4.385127)
							(end 3.0226 -2.2479)
						)
						(arc
							(start 3.0226 -1.55956)
							(mid 3.04227 -1.420177)
							(end 3.099562 -1.29159)
						)
						(arc
							(start 3.099562 -1.29159)
							(mid 4.012804 1.301919)
							(end 3.042158 3.874516)
						)
					)
					(width 0)
					(fill yes)
				)
			)
		)
	)
	(footprint ""
		(layer "F.Cu")
		(at 6.448552 -129.026158)
		(property "Reference" "C12W4"
			(at -0.8382 -0.67818 0)
			(unlocked yes)
			(layer "F.SilkS")
			(effects
				(font
					(size 0.4064 0.254)
					(thickness 0.1524)
				)
				(justify left)
			)
		)
		(property "Value" ""
			(at 0 0 0)
			(layer "F.Fab")
			(effects
				(font
					(size 1.27 1.27)
				)
			)
		)
		(duplicate_pad_numbers_are_jumpers no)
		(fp_poly
			(pts
				(xy 0.3048 -0.1016) (xy 0.3048 0.9906) (xy -0.3048 0.9906) (xy -0.3048 -0.1016)
			)
			(stroke
				(width 0)
				(type default)
			)
			(fill no)
			(layer "F.CrtYd")
		)
		(fp_line
			(start -0.3048 -0.1016)
			(end -0.3048 0.9906)
			(stroke
				(width 0.1)
				(type default)
			)
			(layer "F.Fab")
		)
		(fp_line
			(start -0.3048 0.9906)
			(end 0.3048 0.9906)
			(stroke
				(width 0.1)
				(type default)
			)
			(layer "F.Fab")
		)
		(fp_line
			(start 0.3048 -0.1016)
			(end -0.3048 -0.1016)
			(stroke
				(width 0.1)
				(type default)
			)
			(layer "F.Fab")
		)
		(fp_line
			(start 0.3048 0.9906)
			(end 0.3048 -0.1016)
			(stroke
				(width 0.1)
				(type default)
			)
			(layer "F.Fab")
		)
		(pad "1" smd rect
			(at 0 0)
			(size 0.508 0.508)
			(layers "F.Cu" "F.Mask" "F.Paste")
			(net "VR_PVDDQ_KLM_AIINSEN")
		)
		(pad "2" smd rect
			(at 0 0.889)
			(size 0.508 0.508)
			(layers "F.Cu" "F.Mask" "F.Paste")
			(net "VR_PVDDQ_KLM_VINSEN")
		)
		(zone
			(layer "F.Cu")
			(hatch none 0.5)
			(connect_pads
				(clearance 0)
			)
			(min_thickness 0.25)
			(keepout
				(tracks allowed)
				(vias not_allowed)
				(pads allowed)
				(copperpour not_allowed)
				(footprints allowed)
			)
			(placement
				(enabled no)
				(sheetname "")
			)
			(fill
				(thermal_gap 0.5)
				(thermal_bridge_width 0.5)
				(island_removal_mode 0)
			)
			(polygon
				(pts
					(xy 6.194552 -128.772158) (xy 6.702552 -128.772158) (xy 6.702552 -128.391158) (xy 6.194552 -128.391158)
				)
			)
		)
		(zone
			(layer "F.Cu")
			(hatch none 0.5)
			(connect_pads
				(clearance 0)
			)
			(min_thickness 0.25)
			(keepout
				(tracks not_allowed)
				(vias allowed)
				(pads allowed)
				(copperpour not_allowed)
				(footprints allowed)
			)
			(placement
				(enabled no)
				(sheetname "")
			)
			(fill
				(thermal_gap 0.5)
				(thermal_bridge_width 0.5)
				(island_removal_mode 0)
			)
			(polygon
				(pts
					(xy 6.194552 -128.391158) (xy 6.702552 -128.391158) (xy 6.702552 -128.772158) (xy 6.194552 -128.772158)
				)
			)
		)
	)
)
